# S9S_MB_2U (Grand Teton) — schematic netlist excerpt (pin names and nets, part order shuffled) for the footprints in the layout excerpt that follows; sources: Cadence DE-HDL packaged netlist, KiCad conversion of 03242023_DA0F0TMBIJ0_F0T_Motherboard_J_brd_V01_OCP.brd

PC627  Q_CAP  3300PF 50V 10% X7R  pkg 0402  page 278 : A = SH_PVCCD_HV_CPU0_R ; B = VSENSE_PVCCD_HV_CPU0_DN
ME28  ME_DUMMY_SYMBOL  EFI BIOS LABEL EMPTY  pkg BIOS-BMCLABEL_10-5X10-5  page 312

(kicad_pcb
	(version 20260206)
	(generator "pcbnew")
	(generator_version "10.0")
	(general
		(thickness 1.6)
		(legacy_teardrops no)
	)
	(paper "A4")
	(title_block
		(title "03242023_DA0F0TMBIJ0_F0T_Motherboard_J_brd_V01_OCP.brd")
		(comment 1 "Grand Teton / footprints 2908-2909 of 6105")
	)
	(layers
		(0 "F.Cu" signal "TOP")
		(4 "In1.Cu" signal "GND")
		(6 "In2.Cu" signal "IN1")
		(8 "In3.Cu" signal "GND1")
		(10 "In4.Cu" signal "IN2")
		(12 "In5.Cu" signal "GND2")
		(14 "In6.Cu" signal "IN3")
		(16 "In7.Cu" signal "GND3")
		(18 "In8.Cu" signal "VCC")
		(20 "In9.Cu" signal "VCC1")
		(22 "In10.Cu" signal "GND4")
		(24 "In11.Cu" signal "IN4")
		(26 "In12.Cu" signal "GND5")
		(28 "In13.Cu" signal "IN5")
		(30 "In14.Cu" signal "GND6")
		(32 "In15.Cu" signal "IN6")
		(34 "In16.Cu" signal "GND7")
		(2 "B.Cu" signal "BOTTOM")
		(9 "F.Adhes" user "F.Adhesive")
		(11 "B.Adhes" user "B.Adhesive")
		(13 "F.Paste" user "Package Geometry/Pastemask Top")
		(15 "B.Paste" user "Package Geometry/Pastemask Bottom")
		(5 "F.SilkS" user "Ref Des/Silkscreen Top")
		(7 "B.SilkS" user "Ref Des/Silkscreen Bottom")
		(1 "F.Mask" user "Board Geometry/Soldermask Top")
		(3 "B.Mask" user "Board Geometry/Soldermask Bottom")
		(17 "Dwgs.User" user "User.Drawings")
		(19 "Cmts.User" user "User.Comments")
		(21 "Eco1.User" user "User.Eco1")
		(23 "Eco2.User" user "User.Eco2")
		(25 "Edge.Cuts" user "Board Geometry/Outline")
		(27 "Margin" user)
		(31 "F.CrtYd" user "Package Geometry/Place Bound Top")
		(29 "B.CrtYd" user "Package Geometry/Place Bound Bottom")
		(35 "F.Fab" user "Ref Des/Assembly Top")
		(33 "B.Fab" user "Ref Des/Assembly Bottom")
	)
	(footprint ""
		(layer "F.Cu")
		(at 434.86832 -126.850648 180)
		(property "Reference" "PC627"
			(at 0 0 180)
			(layer "F.SilkS")
			(hide yes)
			(effects
				(font
					(size 1.27 1.27)
				)
			)
		)
		(property "Value" ""
			(at 0 0 180)
			(layer "F.Fab")
			(effects
				(font
					(size 1.27 1.27)
				)
			)
		)
		(duplicate_pad_numbers_are_jumpers no)
		(fp_line
			(start 0.7874 0.4064)
			(end -0.7874 0.4064)
			(stroke
				(width 0.1524)
				(type default)
			)
			(layer "F.SilkS")
		)
		(fp_line
			(start 0.7874 -0.4064)
			(end 0.7874 0.4064)
			(stroke
				(width 0.1524)
				(type default)
			)
			(layer "F.SilkS")
		)
		(fp_line
			(start -0.7874 0.4064)
			(end -0.7874 -0.4064)
			(stroke
				(width 0.1524)
				(type default)
			)
			(layer "F.SilkS")
		)
		(fp_line
			(start -0.7874 -0.4064)
			(end 0.7874 -0.4064)
			(stroke
				(width 0.1524)
				(type default)
			)
			(layer "F.SilkS")
		)
		(fp_line
			(start 0.67945 0.3048)
			(end 0.120396 0.3048)
			(stroke
				(width 0.1)
				(type default)
			)
			(layer "F.Fab")
		)
		(fp_line
			(start 0.67945 -0.3048)
			(end 0.67945 0.3048)
			(stroke
				(width 0.1)
				(type default)
			)
			(layer "F.Fab")
		)
		(fp_line
			(start 0.12065 -0.2794)
			(end 0.12065 -0.3048)
			(stroke
				(width 0.1)
				(type default)
			)
			(layer "F.Fab")
		)
		(fp_line
			(start 0.12065 -0.3048)
			(end 0.67945 -0.3048)
			(stroke
				(width 0.1)
				(type default)
			)
			(layer "F.Fab")
		)
		(fp_line
			(start 0.120396 0.3048)
			(end 0.120396 0.2794)
			(stroke
				(width 0.1)
				(type default)
			)
			(layer "F.Fab")
		)
		(fp_line
			(start 0.120396 0.2794)
			(end -0.12065 0.2794)
			(stroke
				(width 0.1)
				(type default)
			)
			(layer "F.Fab")
		)
		(fp_line
			(start -0.12065 0.3048)
			(end -0.67945 0.3048)
			(stroke
				(width 0.1)
				(type default)
			)
			(layer "F.Fab")
		)
		(fp_line
			(start -0.12065 0.2794)
			(end -0.12065 0.3048)
			(stroke
				(width 0.1)
				(type default)
			)
			(layer "F.Fab")
		)
		(fp_line
			(start -0.12065 -0.2794)
			(end 0.12065 -0.2794)
			(stroke
				(width 0.1)
				(type default)
			)
			(layer "F.Fab")
		)
		(fp_line
			(start -0.12065 -0.305054)
			(end -0.12065 -0.2794)
			(stroke
				(width 0.1)
				(type default)
			)
			(layer "F.Fab")
		)
		(fp_line
			(start -0.67945 0.3048)
			(end -0.67945 -0.305054)
			(stroke
				(width 0.1)
				(type default)
			)
			(layer "F.Fab")
		)
		(fp_line
			(start -0.67945 -0.305054)
			(end -0.12065 -0.305054)
			(stroke
				(width 0.1)
				(type default)
			)
			(layer "F.Fab")
		)
		(pad "1" smd circle
			(at -0.40005 0 180)
			(size 0 0)
			(layers "F.Cu" "F.Mask" "F.Paste")
			(net "SH_PVCCD_HV_CPU0_R")
		)
		(pad "2" smd circle
			(at 0.40005 0 180)
			(size 0 0)
			(layers "F.Cu" "F.Mask" "F.Paste")
			(net "VSENSE_PVCCD_HV_CPU0_DN")
		)
	)
	(footprint ""
		(layer "F.Cu")
		(at 435.42712 -395.87678)
		(property "Reference" "ME28"
			(at 0 0 0)
			(layer "F.SilkS")
			(hide yes)
			(effects
				(font
					(size 1.27 1.27)
				)
			)
		)
		(property "Value" ""
			(at 0 0 0)
			(layer "F.Fab")
			(effects
				(font
					(size 1.27 1.27)
				)
			)
		)
		(duplicate_pad_numbers_are_jumpers no)
		(fp_line
			(start 0 -10.500106)
			(end 1.524 -10.500106)
			(stroke
				(width 0.1524)
				(type default)
			)
			(layer "F.SilkS")
		)
		(fp_line
			(start 0 -8.976106)
			(end 0 -10.500106)
			(stroke
				(width 0.1524)
				(type default)
			)
			(layer "F.SilkS")
		)
		(fp_line
			(start 0 0)
			(end 0 -1.524)
			(stroke
				(width 0.1524)
				(type default)
			)
			(layer "F.SilkS")
		)
		(fp_line
			(start 1.524 0)
			(end 0 0)
			(stroke
				(width 0.1524)
				(type default)
			)
			(layer "F.SilkS")
		)
		(fp_line
			(start 8.976106 0)
			(end 10.500106 0)
			(stroke
				(width 0.1524)
				(type default)
			)
			(layer "F.SilkS")
		)
		(fp_line
			(start 10.500106 -10.500106)
			(end 8.976106 -10.500106)
			(stroke
				(width 0.1524)
				(type default)
			)
			(layer "F.SilkS")
		)
		(fp_line
			(start 10.500106 -8.976106)
			(end 10.500106 -10.500106)
			(stroke
				(width 0.1524)
				(type default)
			)
			(layer "F.SilkS")
		)
		(fp_line
			(start 10.500106 0)
			(end 10.500106 -1.524)
			(stroke
				(width 0.1524)
				(type default)
			)
			(layer "F.SilkS")
		)
		(fp_text user "BIOS"
			(at 1.681226 -8.494776 0)
			(unlocked yes)
			(layer "F.SilkS")
			(effects
				(font
					(size 1.905 1.4224)
					(thickness 0.1524)
				)
				(justify left)
			)
		)
		(fp_text user "BMC"
			(at 2.303526 -1.865376 0)
			(unlocked yes)
			(layer "F.SilkS")
			(effects
				(font
					(size 1.905 1.4224)
					(thickness 0.1524)
				)
				(justify left)
			)
		)
		(fp_text user "&"
			(at 4.183126 -5.624576 0)
			(unlocked yes)
			(layer "F.SilkS")
			(effects
				(font
					(size 1.905 1.4224)
					(thickness 0.1524)
				)
				(justify left)
			)
		)
		(zone
			(layer "F.Cu")
			(hatch none 0.5)
			(connect_pads
				(clearance 0)
			)
			(min_thickness 0.25)
			(keepout
				(tracks not_allowed)
				(vias allowed)
				(pads allowed)
				(copperpour not_allowed)
				(footprints allowed)
			)
			(placement
				(enabled no)
				(sheetname "")
			)
			(fill
				(thermal_gap 0.5)
				(thermal_bridge_width 0.5)
				(island_removal_mode 0)
			)
			(polygon
				(pts
					(xy 435.42712 -395.87678) (xy 445.927226 -395.87678) (xy 445.927226 -406.376886) (xy 435.42712 -406.376886)
				)
			)
		)
	)
)
